# S9S_MB_2U (Grand Teton) — schematic netlist excerpt (pin names and nets, part order shuffled) for the footprints in the layout excerpt that follows; sources: Cadence DE-HDL packaged netlist, KiCad conversion of 03242023_DA0F0TMBIJ0_F0T_Motherboard_J_brd_V01_OCP.brd

R3683  Q_RES  0 5% EMPTY  pkg 0402LF  page 250 : A = P3V3_ADC ; B = P3V3_ADC_MAM
R3431  Q_RES  100K 1% EMPTY  pkg 0402LF  page 147 : A = GPU_HMC_PRSNT_N ; B = GND
PC2220  Q_CAP  10UF 16V 10% X6S  pkg C0805  page 192 : A = P3V3_E1S_0_R ; B = GND

(kicad_pcb
	(version 20260206)
	(generator "pcbnew")
	(generator_version "10.0")
	(general
		(thickness 1.6)
		(legacy_teardrops no)
	)
	(paper "A4")
	(title_block
		(title "03242023_DA0F0TMBIJ0_F0T_Motherboard_J_brd_V01_OCP.brd")
		(comment 1 "Grand Teton / footprints 3672-3674 of 6105")
	)
	(layers
		(0 "F.Cu" signal "TOP")
		(4 "In1.Cu" signal "GND")
		(6 "In2.Cu" signal "IN1")
		(8 "In3.Cu" signal "GND1")
		(10 "In4.Cu" signal "IN2")
		(12 "In5.Cu" signal "GND2")
		(14 "In6.Cu" signal "IN3")
		(16 "In7.Cu" signal "GND3")
		(18 "In8.Cu" signal "VCC")
		(20 "In9.Cu" signal "VCC1")
		(22 "In10.Cu" signal "GND4")
		(24 "In11.Cu" signal "IN4")
		(26 "In12.Cu" signal "GND5")
		(28 "In13.Cu" signal "IN5")
		(30 "In14.Cu" signal "GND6")
		(32 "In15.Cu" signal "IN6")
		(34 "In16.Cu" signal "GND7")
		(2 "B.Cu" signal "BOTTOM")
		(9 "F.Adhes" user "F.Adhesive")
		(11 "B.Adhes" user "B.Adhesive")
		(13 "F.Paste" user "Package Geometry/Pastemask Top")
		(15 "B.Paste" user "Package Geometry/Pastemask Bottom")
		(5 "F.SilkS" user "Ref Des/Silkscreen Top")
		(7 "B.SilkS" user "Ref Des/Silkscreen Bottom")
		(1 "F.Mask" user "Board Geometry/Soldermask Top")
		(3 "B.Mask" user "Board Geometry/Soldermask Bottom")
		(17 "Dwgs.User" user "User.Drawings")
		(19 "Cmts.User" user "User.Comments")
		(21 "Eco1.User" user "User.Eco1")
		(23 "Eco2.User" user "User.Eco2")
		(25 "Edge.Cuts" user "Board Geometry/Outline")
		(27 "Margin" user)
		(31 "F.CrtYd" user "Package Geometry/Place Bound Top")
		(29 "B.CrtYd" user "Package Geometry/Place Bound Bottom")
		(35 "F.Fab" user "Ref Des/Assembly Top")
		(33 "B.Fab" user "Ref Des/Assembly Bottom")
	)
	(footprint ""
		(layer "F.Cu")
		(at 40.627554 -108.047282)
		(property "Reference" "R3683"
			(at 0 0 0)
			(layer "F.SilkS")
			(hide yes)
			(effects
				(font
					(size 1.27 1.27)
				)
			)
		)
		(property "Value" ""
			(at 0 0 0)
			(layer "F.Fab")
			(effects
				(font
					(size 1.27 1.27)
				)
			)
		)
		(duplicate_pad_numbers_are_jumpers no)
		(fp_line
			(start -0.7874 -0.4064)
			(end 0.7874 -0.4064)
			(stroke
				(width 0.1524)
				(type default)
			)
			(layer "F.SilkS")
		)
		(fp_line
			(start -0.7874 0.4064)
			(end -0.7874 -0.4064)
			(stroke
				(width 0.1524)
				(type default)
			)
			(layer "F.SilkS")
		)
		(fp_line
			(start 0.7874 -0.4064)
			(end 0.7874 0.4064)
			(stroke
				(width 0.1524)
				(type default)
			)
			(layer "F.SilkS")
		)
		(fp_line
			(start 0.7874 0.4064)
			(end -0.7874 0.4064)
			(stroke
				(width 0.1524)
				(type default)
			)
			(layer "F.SilkS")
		)
		(fp_line
			(start -0.67945 -0.305054)
			(end -0.12065 -0.305054)
			(stroke
				(width 0.1)
				(type default)
			)
			(layer "F.Fab")
		)
		(fp_line
			(start -0.67945 0.3048)
			(end -0.67945 -0.305054)
			(stroke
				(width 0.1)
				(type default)
			)
			(layer "F.Fab")
		)
		(fp_line
			(start -0.12065 -0.305054)
			(end -0.12065 -0.2794)
			(stroke
				(width 0.1)
				(type default)
			)
			(layer "F.Fab")
		)
		(fp_line
			(start -0.12065 -0.2794)
			(end 0.12065 -0.2794)
			(stroke
				(width 0.1)
				(type default)
			)
			(layer "F.Fab")
		)
		(fp_line
			(start -0.12065 0.2794)
			(end -0.12065 0.3048)
			(stroke
				(width 0.1)
				(type default)
			)
			(layer "F.Fab")
		)
		(fp_line
			(start -0.12065 0.3048)
			(end -0.67945 0.3048)
			(stroke
				(width 0.1)
				(type default)
			)
			(layer "F.Fab")
		)
		(fp_line
			(start 0.120396 0.2794)
			(end -0.12065 0.2794)
			(stroke
				(width 0.1)
				(type default)
			)
			(layer "F.Fab")
		)
		(fp_line
			(start 0.120396 0.3048)
			(end 0.120396 0.2794)
			(stroke
				(width 0.1)
				(type default)
			)
			(layer "F.Fab")
		)
		(fp_line
			(start 0.12065 -0.3048)
			(end 0.67945 -0.3048)
			(stroke
				(width 0.1)
				(type default)
			)
			(layer "F.Fab")
		)
		(fp_line
			(start 0.12065 -0.2794)
			(end 0.12065 -0.3048)
			(stroke
				(width 0.1)
				(type default)
			)
			(layer "F.Fab")
		)
		(fp_line
			(start 0.67945 -0.3048)
			(end 0.67945 0.3048)
			(stroke
				(width 0.1)
				(type default)
			)
			(layer "F.Fab")
		)
		(fp_line
			(start 0.67945 0.3048)
			(end 0.120396 0.3048)
			(stroke
				(width 0.1)
				(type default)
			)
			(layer "F.Fab")
		)
		(pad "1" smd rect
			(at -0.40005 0 180)
			(size 0.4572 0.508)
			(layers "F.Cu" "F.Mask" "F.Paste")
			(net "P3V3_ADC")
		)
		(pad "2" smd rect
			(at 0.40005 0 180)
			(size 0.4572 0.508)
			(layers "F.Cu" "F.Mask" "F.Paste")
			(net "P3V3_ADC_MAM")
		)
	)
	(footprint ""
		(layer "F.Cu")
		(at 218.205304 -59.453272 180)
		(property "Reference" "PC2220"
			(at 0 0 180)
			(layer "F.SilkS")
			(hide yes)
			(effects
				(font
					(size 1.27 1.27)
				)
			)
		)
		(property "Value" ""
			(at 0 0 180)
			(layer "F.Fab")
			(effects
				(font
					(size 1.27 1.27)
				)
			)
		)
		(duplicate_pad_numbers_are_jumpers no)
		(fp_line
			(start 1.524 0.762)
			(end -1.524 0.762)
			(stroke
				(width 0.1524)
				(type default)
			)
			(layer "F.SilkS")
		)
		(fp_line
			(start 1.524 -0.762)
			(end 1.524 0.762)
			(stroke
				(width 0.1524)
				(type default)
			)
			(layer "F.SilkS")
		)
		(fp_line
			(start -1.524 0.762)
			(end -1.524 -0.762)
			(stroke
				(width 0.1524)
				(type default)
			)
			(layer "F.SilkS")
		)
		(fp_line
			(start -1.524 -0.762)
			(end 1.524 -0.762)
			(stroke
				(width 0.1524)
				(type default)
			)
			(layer "F.SilkS")
		)
		(fp_line
			(start 1.1049 0.724916)
			(end 1.1049 -0.724916)
			(stroke
				(width 0.1)
				(type default)
			)
			(layer "F.Fab")
		)
		(fp_line
			(start 1.1049 -0.724916)
			(end -1.1049 -0.724916)
			(stroke
				(width 0.1)
				(type default)
			)
			(layer "F.Fab")
		)
		(fp_line
			(start -1.1049 0.724916)
			(end 1.1049 0.724916)
			(stroke
				(width 0.1)
				(type default)
			)
			(layer "F.Fab")
		)
		(fp_line
			(start -1.1049 -0.724916)
			(end -1.1049 0.724916)
			(stroke
				(width 0.1)
				(type default)
			)
			(layer "F.Fab")
		)
		(pad "1" smd rect
			(at -0.889 0)
			(size 1.016 1.27)
			(layers "F.Cu" "F.Mask" "F.Paste")
			(net "P3V3_E1S_0_R")
		)
		(pad "2" smd rect
			(at 0.889 0)
			(size 1.016 1.27)
			(layers "F.Cu" "F.Mask" "F.Paste")
			(net "GND")
		)
	)
	(footprint ""
		(layer "F.Cu")
		(at 176.059338 -414.697418)
		(property "Reference" "R3431"
			(at 0 0 0)
			(layer "F.SilkS")
			(hide yes)
			(effects
				(font
					(size 1.27 1.27)
				)
			)
		)
		(property "Value" ""
			(at 0 0 0)
			(layer "F.Fab")
			(effects
				(font
					(size 1.27 1.27)
				)
			)
		)
		(duplicate_pad_numbers_are_jumpers no)
		(fp_line
			(start -0.7874 -0.4064)
			(end 0.7874 -0.4064)
			(stroke
				(width 0.1524)
				(type default)
			)
			(layer "F.SilkS")
		)
		(fp_line
			(start -0.7874 0.4064)
			(end -0.7874 -0.4064)
			(stroke
				(width 0.1524)
				(type default)
			)
			(layer "F.SilkS")
		)
		(fp_line
			(start 0.7874 -0.4064)
			(end 0.7874 0.4064)
			(stroke
				(width 0.1524)
				(type default)
			)
			(layer "F.SilkS")
		)
		(fp_line
			(start 0.7874 0.4064)
			(end -0.7874 0.4064)
			(stroke
				(width 0.1524)
				(type default)
			)
			(layer "F.SilkS")
		)
		(fp_line
			(start -0.67945 -0.305054)
			(end -0.12065 -0.305054)
			(stroke
				(width 0.1)
				(type default)
			)
			(layer "F.Fab")
		)
		(fp_line
			(start -0.67945 0.3048)
			(end -0.67945 -0.305054)
			(stroke
				(width 0.1)
				(type default)
			)
			(layer "F.Fab")
		)
		(fp_line
			(start -0.12065 -0.305054)
			(end -0.12065 -0.2794)
			(stroke
				(width 0.1)
				(type default)
			)
			(layer "F.Fab")
		)
		(fp_line
			(start -0.12065 -0.2794)
			(end 0.12065 -0.2794)
			(stroke
				(width 0.1)
				(type default)
			)
			(layer "F.Fab")
		)
		(fp_line
			(start -0.12065 0.2794)
			(end -0.12065 0.3048)
			(stroke
				(width 0.1)
				(type default)
			)
			(layer "F.Fab")
		)
		(fp_line
			(start -0.12065 0.3048)
			(end -0.67945 0.3048)
			(stroke
				(width 0.1)
				(type default)
			)
			(layer "F.Fab")
		)
		(fp_line
			(start 0.120396 0.2794)
			(end -0.12065 0.2794)
			(stroke
				(width 0.1)
				(type default)
			)
			(layer "F.Fab")
		)
		(fp_line
			(start 0.120396 0.3048)
			(end 0.120396 0.2794)
			(stroke
				(width 0.1)
				(type default)
			)
			(layer "F.Fab")
		)
		(fp_line
			(start 0.12065 -0.3048)
			(end 0.67945 -0.3048)
			(stroke
				(width 0.1)
				(type default)
			)
			(layer "F.Fab")
		)
		(fp_line
			(start 0.12065 -0.2794)
			(end 0.12065 -0.3048)
			(stroke
				(width 0.1)
				(type default)
			)
			(layer "F.Fab")
		)
		(fp_line
			(start 0.67945 -0.3048)
			(end 0.67945 0.3048)
			(stroke
				(width 0.1)
				(type default)
			)
			(layer "F.Fab")
		)
		(fp_line
			(start 0.67945 0.3048)
			(end 0.120396 0.3048)
			(stroke
				(width 0.1)
				(type default)
			)
			(layer "F.Fab")
		)
		(pad "1" smd circle
			(at -0.40005 0)
			(size 0 0)
			(layers "F.Cu" "F.Mask" "F.Paste")
			(net "GPU_HMC_PRSNT_N")
		)
		(pad "2" smd circle
			(at 0.40005 0)
			(size 0 0)
			(layers "F.Cu" "F.Mask" "F.Paste")
			(net "GND")
		)
	)
)
